(kicad_pcb
	(version 20260206)
	(generator "pcbnew")
	(generator_version "10.0")
	(general
		(thickness 1.6)
		(legacy_teardrops no)
	)
	(paper "A4")
	(title_block
		(title "01162023_DA0F0TEBIF0_F0T_Expander_BD_F_brd_V02_OCP.brd")
		(comment 1 "Grand Teton / footprints 2021-2021 of 9728")
	)
	(layers
		(0 "F.Cu" signal "TOP")
		(4 "In1.Cu" signal "GND")
		(6 "In2.Cu" signal "VCC")
		(8 "In3.Cu" signal "VCC1")
		(10 "In4.Cu" signal "GND1")
		(12 "In5.Cu" signal "IN1")
		(14 "In6.Cu" signal "GND2")
		(16 "In7.Cu" signal "IN2")
		(18 "In8.Cu" signal "GND3")
		(20 "In9.Cu" signal "IN3")
		(22 "In10.Cu" signal "GND4")
		(24 "In11.Cu" signal "IN4")
		(26 "In12.Cu" signal "GND5")
		(28 "In13.Cu" signal "IN5")
		(30 "In14.Cu" signal "GND6")
		(32 "In15.Cu" signal "IN6")
		(34 "In16.Cu" signal "GND7")
		(2 "B.Cu" signal "BOTTOM")
		(9 "F.Adhes" user "F.Adhesive")
		(11 "B.Adhes" user "B.Adhesive")
		(13 "F.Paste" user "Package Geometry/Pastemask Top")
		(15 "B.Paste" user "Package Geometry/Pastemask Bottom")
		(5 "F.SilkS" user "Ref Des/Silkscreen Top")
		(7 "B.SilkS" user "Ref Des/Silkscreen Bottom")
		(1 "F.Mask" user "Board Geometry/Soldermask Top")
		(3 "B.Mask" user "Board Geometry/Soldermask Bottom")
		(17 "Dwgs.User" user "User.Drawings")
		(19 "Cmts.User" user "User.Comments")
		(21 "Eco1.User" user "User.Eco1")
		(23 "Eco2.User" user "User.Eco2")
		(25 "Edge.Cuts" user "Board Geometry/Outline")
		(27 "Margin" user)
		(31 "F.CrtYd" user "Package Geometry/Place Bound Top")
		(29 "B.CrtYd" user "Package Geometry/Place Bound Bottom")
		(35 "F.Fab" user "Ref Des/Assembly Top")
		(33 "B.Fab" user "Ref Des/Assembly Bottom")
	)
	(footprint ""
		(layer "F.Cu")
		(at 234.040172 -32.848042 90)
		(property "Reference" "PC945"
			(at 0 0 90)
			(layer "F.SilkS")
			(hide yes)
			(effects
				(font
					(size 1.27 1.27)
				)
			)
		)
		(property "Value" ""
			(at 0 0 90)
			(layer "F.Fab")
			(effects
				(font
					(size 1.27 1.27)
				)
			)
		)
		(duplicate_pad_numbers_are_jumpers no)
		(fp_line
			(start 0.7874 -0.4064)
			(end 0.7874 0.4064)
			(stroke
				(width 0.1524)
				(type default)
			)
			(layer "F.SilkS")
		)
		(fp_line
			(start -0.7874 -0.4064)
			(end 0.7874 -0.4064)
			(stroke
				(width 0.1524)
				(type default)
			)
			(layer "F.SilkS")
		)
		(fp_line
			(start 0.7874 0.4064)
			(end -0.7874 0.4064)
			(stroke
				(width 0.1524)
				(type default)
			)
			(layer "F.SilkS")
		)
		(fp_line
			(start -0.7874 0.4064)
			(end -0.7874 -0.4064)
			(stroke
				(width 0.1524)
				(type default)
			)
			(layer "F.SilkS")
		)
		(fp_line
			(start -0.12065 -0.305054)
			(end -0.12065 -0.2794)
			(stroke
				(width 0.1)
				(type default)
			)
			(layer "F.Fab")
		)
		(fp_line
			(start -0.67945 -0.305054)
			(end -0.12065 -0.305054)
			(stroke
				(width 0.1)
				(type default)
			)
			(layer "F.Fab")
		)
		(fp_line
			(start 0.67945 -0.3048)
			(end 0.67945 0.3048)
			(stroke
				(width 0.1)
				(type default)
			)
			(layer "F.Fab")
		)
		(fp_line
			(start 0.12065 -0.3048)
			(end 0.67945 -0.3048)
			(stroke
				(width 0.1)
				(type default)
			)
			(layer "F.Fab")
		)
		(fp_line
			(start 0.12065 -0.2794)
			(end 0.12065 -0.3048)
			(stroke
				(width 0.1)
				(type default)
			)
			(layer "F.Fab")
		)
		(fp_line
			(start -0.12065 -0.2794)
			(end 0.12065 -0.2794)
			(stroke
				(width 0.1)
				(type default)
			)
			(layer "F.Fab")
		)
		(fp_line
			(start 0.120396 0.2794)
			(end -0.12065 0.2794)
			(stroke
				(width 0.1)
				(type default)
			)
			(layer "F.Fab")
		)
		(fp_line
			(start -0.12065 0.2794)
			(end -0.12065 0.3048)
			(stroke
				(width 0.1)
				(type default)
			)
			(layer "F.Fab")
		)
		(fp_line
			(start 0.67945 0.3048)
			(end 0.120396 0.3048)
			(stroke
				(width 0.1)
				(type default)
			)
			(layer "F.Fab")
		)
		(fp_line
			(start 0.120396 0.3048)
			(end 0.120396 0.2794)
			(stroke
				(width 0.1)
				(type default)
			)
			(layer "F.Fab")
		)
		(fp_line
			(start -0.12065 0.3048)
			(end -0.67945 0.3048)
			(stroke
				(width 0.1)
				(type default)
			)
			(layer "F.Fab")
		)
		(fp_line
			(start -0.67945 0.3048)
			(end -0.67945 -0.305054)
			(stroke
				(width 0.1)
				(type default)
			)
			(layer "F.Fab")
		)
		(pad "1" smd circle
			(at -0.40005 0 90)
			(size 0 0)
			(layers "F.Cu" "F.Mask" "F.Paste")
			(net "P3V3_SSD8_CO_DV_DT")
		)
		(pad "2" smd circle
			(at 0.40005 0 90)
			(size 0 0)
			(layers "F.Cu" "F.Mask" "F.Paste")
			(net "GND")
		)
	)
)
